# T6G (Grand Teton) — schematic netlist excerpt (pin names and nets, part order shuffled) for the footprints in the layout excerpt that follows; sources: Cadence DE-HDL packaged netlist, KiCad conversion of 04192023_DAF0TMB3IC0_F0TG_MB_C_brd_V02_OCP.brd

R3613  Q_RES  4.7K 1% EMPTY  pkg 0402LF  page 237 : A = GND ; B = INA230_5_A0
R4137  Q_RES  4.7K 5% CHIP  pkg 0402LF  page 125 : A = P3V3_AUX ; B = GPU_3V3IO_RSVD3_FFU_N

(kicad_pcb
	(version 20260206)
	(generator "pcbnew")
	(generator_version "10.0")
	(general
		(thickness 1.6)
		(legacy_teardrops no)
	)
	(paper "A4")
	(title_block
		(title "04192023_DAF0TMB3IC0_F0TG_MB_C_brd_V02_OCP.brd")
		(comment 1 "Grand Teton / footprints 3239-3240 of 8354")
	)
	(layers
		(0 "F.Cu" signal "TOP")
		(4 "In1.Cu" signal "GND")
		(6 "In2.Cu" signal "IN1")
		(8 "In3.Cu" signal "GND1")
		(10 "In4.Cu" signal "IN2")
		(12 "In5.Cu" signal "GND2")
		(14 "In6.Cu" signal "IN3")
		(16 "In7.Cu" signal "GND3")
		(18 "In8.Cu" signal "VCC")
		(20 "In9.Cu" signal "VCC1")
		(22 "In10.Cu" signal "GND4")
		(24 "In11.Cu" signal "IN4")
		(26 "In12.Cu" signal "GND5")
		(28 "In13.Cu" signal "IN5")
		(30 "In14.Cu" signal "GND6")
		(32 "In15.Cu" signal "IN6")
		(34 "In16.Cu" signal "GND7")
		(2 "B.Cu" signal "BOTTOM")
		(9 "F.Adhes" user "F.Adhesive")
		(11 "B.Adhes" user "B.Adhesive")
		(13 "F.Paste" user "Package Geometry/Pastemask Top")
		(15 "B.Paste" user "Package Geometry/Pastemask Bottom")
		(5 "F.SilkS" user "Ref Des/Silkscreen Top")
		(7 "B.SilkS" user "Ref Des/Silkscreen Bottom")
		(1 "F.Mask" user "Board Geometry/Soldermask Top")
		(3 "B.Mask" user "Board Geometry/Soldermask Bottom")
		(17 "Dwgs.User" user "User.Drawings")
		(19 "Cmts.User" user "User.Comments")
		(21 "Eco1.User" user "User.Eco1")
		(23 "Eco2.User" user "User.Eco2")
		(25 "Edge.Cuts" user "Board Geometry/Outline")
		(27 "Margin" user)
		(31 "F.CrtYd" user "Package Geometry/Place Bound Top")
		(29 "B.CrtYd" user "Package Geometry/Place Bound Bottom")
		(35 "F.Fab" user "Ref Des/Assembly Top")
		(33 "B.Fab" user "Ref Des/Assembly Bottom")
	)
	(footprint ""
		(layer "F.Cu")
		(at 211.102956 -30.276292 90)
		(property "Reference" "R3613"
			(at 0 0 90)
			(layer "F.SilkS")
			(hide yes)
			(effects
				(font
					(size 1.27 1.27)
				)
			)
		)
		(property "Value" ""
			(at 0 0 90)
			(layer "F.Fab")
			(effects
				(font
					(size 1.27 1.27)
				)
			)
		)
		(duplicate_pad_numbers_are_jumpers no)
		(fp_line
			(start 0.7874 -0.4064)
			(end 0.7874 0.4064)
			(stroke
				(width 0.1524)
				(type default)
			)
			(layer "F.SilkS")
		)
		(fp_line
			(start -0.7874 -0.4064)
			(end 0.7874 -0.4064)
			(stroke
				(width 0.1524)
				(type default)
			)
			(layer "F.SilkS")
		)
		(fp_line
			(start 0.7874 0.4064)
			(end -0.7874 0.4064)
			(stroke
				(width 0.1524)
				(type default)
			)
			(layer "F.SilkS")
		)
		(fp_line
			(start -0.7874 0.4064)
			(end -0.7874 -0.4064)
			(stroke
				(width 0.1524)
				(type default)
			)
			(layer "F.SilkS")
		)
		(fp_line
			(start -0.12065 -0.305054)
			(end -0.12065 -0.2794)
			(stroke
				(width 0.1)
				(type default)
			)
			(layer "F.Fab")
		)
		(fp_line
			(start -0.67945 -0.305054)
			(end -0.12065 -0.305054)
			(stroke
				(width 0.1)
				(type default)
			)
			(layer "F.Fab")
		)
		(fp_line
			(start 0.67945 -0.3048)
			(end 0.67945 0.3048)
			(stroke
				(width 0.1)
				(type default)
			)
			(layer "F.Fab")
		)
		(fp_line
			(start 0.12065 -0.3048)
			(end 0.67945 -0.3048)
			(stroke
				(width 0.1)
				(type default)
			)
			(layer "F.Fab")
		)
		(fp_line
			(start 0.12065 -0.2794)
			(end 0.12065 -0.3048)
			(stroke
				(width 0.1)
				(type default)
			)
			(layer "F.Fab")
		)
		(fp_line
			(start -0.12065 -0.2794)
			(end 0.12065 -0.2794)
			(stroke
				(width 0.1)
				(type default)
			)
			(layer "F.Fab")
		)
		(fp_line
			(start 0.120396 0.2794)
			(end -0.12065 0.2794)
			(stroke
				(width 0.1)
				(type default)
			)
			(layer "F.Fab")
		)
		(fp_line
			(start -0.12065 0.2794)
			(end -0.12065 0.3048)
			(stroke
				(width 0.1)
				(type default)
			)
			(layer "F.Fab")
		)
		(fp_line
			(start 0.67945 0.3048)
			(end 0.120396 0.3048)
			(stroke
				(width 0.1)
				(type default)
			)
			(layer "F.Fab")
		)
		(fp_line
			(start 0.120396 0.3048)
			(end 0.120396 0.2794)
			(stroke
				(width 0.1)
				(type default)
			)
			(layer "F.Fab")
		)
		(fp_line
			(start -0.12065 0.3048)
			(end -0.67945 0.3048)
			(stroke
				(width 0.1)
				(type default)
			)
			(layer "F.Fab")
		)
		(fp_line
			(start -0.67945 0.3048)
			(end -0.67945 -0.305054)
			(stroke
				(width 0.1)
				(type default)
			)
			(layer "F.Fab")
		)
		(pad "1" smd circle
			(at -0.40005 0 90)
			(size 0 0)
			(layers "F.Cu" "F.Mask" "F.Paste")
			(net "GND")
		)
		(pad "2" smd circle
			(at 0.40005 0 90)
			(size 0 0)
			(layers "F.Cu" "F.Mask" "F.Paste")
			(net "INA230_5_A0")
		)
	)
	(footprint ""
		(layer "F.Cu")
		(at 302.60417 -424.9547)
		(property "Reference" "R4137"
			(at 0 0 0)
			(layer "F.SilkS")
			(hide yes)
			(effects
				(font
					(size 1.27 1.27)
				)
			)
		)
		(property "Value" ""
			(at 0 0 0)
			(layer "F.Fab")
			(effects
				(font
					(size 1.27 1.27)
				)
			)
		)
		(duplicate_pad_numbers_are_jumpers no)
		(fp_line
			(start -0.7874 -0.4064)
			(end 0.7874 -0.4064)
			(stroke
				(width 0.1524)
				(type default)
			)
			(layer "F.SilkS")
		)
		(fp_line
			(start -0.7874 0.4064)
			(end -0.7874 -0.4064)
			(stroke
				(width 0.1524)
				(type default)
			)
			(layer "F.SilkS")
		)
		(fp_line
			(start 0.7874 -0.4064)
			(end 0.7874 0.4064)
			(stroke
				(width 0.1524)
				(type default)
			)
			(layer "F.SilkS")
		)
		(fp_line
			(start 0.7874 0.4064)
			(end -0.7874 0.4064)
			(stroke
				(width 0.1524)
				(type default)
			)
			(layer "F.SilkS")
		)
		(fp_line
			(start -0.67945 -0.305054)
			(end -0.12065 -0.305054)
			(stroke
				(width 0.1)
				(type default)
			)
			(layer "F.Fab")
		)
		(fp_line
			(start -0.67945 0.3048)
			(end -0.67945 -0.305054)
			(stroke
				(width 0.1)
				(type default)
			)
			(layer "F.Fab")
		)
		(fp_line
			(start -0.12065 -0.305054)
			(end -0.12065 -0.2794)
			(stroke
				(width 0.1)
				(type default)
			)
			(layer "F.Fab")
		)
		(fp_line
			(start -0.12065 -0.2794)
			(end 0.12065 -0.2794)
			(stroke
				(width 0.1)
				(type default)
			)
			(layer "F.Fab")
		)
		(fp_line
			(start -0.12065 0.2794)
			(end -0.12065 0.3048)
			(stroke
				(width 0.1)
				(type default)
			)
			(layer "F.Fab")
		)
		(fp_line
			(start -0.12065 0.3048)
			(end -0.67945 0.3048)
			(stroke
				(width 0.1)
				(type default)
			)
			(layer "F.Fab")
		)
		(fp_line
			(start 0.120396 0.2794)
			(end -0.12065 0.2794)
			(stroke
				(width 0.1)
				(type default)
			)
			(layer "F.Fab")
		)
		(fp_line
			(start 0.120396 0.3048)
			(end 0.120396 0.2794)
			(stroke
				(width 0.1)
				(type default)
			)
			(layer "F.Fab")
		)
		(fp_line
			(start 0.12065 -0.3048)
			(end 0.67945 -0.3048)
			(stroke
				(width 0.1)
				(type default)
			)
			(layer "F.Fab")
		)
		(fp_line
			(start 0.12065 -0.2794)
			(end 0.12065 -0.3048)
			(stroke
				(width 0.1)
				(type default)
			)
			(layer "F.Fab")
		)
		(fp_line
			(start 0.67945 -0.3048)
			(end 0.67945 0.3048)
			(stroke
				(width 0.1)
				(type default)
			)
			(layer "F.Fab")
		)
		(fp_line
			(start 0.67945 0.3048)
			(end 0.120396 0.3048)
			(stroke
				(width 0.1)
				(type default)
			)
			(layer "F.Fab")
		)
		(pad "1" smd circle
			(at -0.40005 0)
			(size 0 0)
			(layers "F.Cu" "F.Mask" "F.Paste")
			(net "P3V3_AUX")
		)
		(pad "2" smd circle
			(at 0.40005 0)
			(size 0 0)
			(layers "F.Cu" "F.Mask" "F.Paste")
			(net "GPU_3V3IO_RSVD3_FFU_N")
		)
	)
)
